# T6G (Grand Teton) — schematic netlist excerpt (pin names and nets, part order shuffled) for the footprints in the layout excerpt that follows; sources: Cadence DE-HDL packaged netlist, KiCad conversion of 04192023_DAF0TMB3IC0_F0TG_MB_C_brd_V02_OCP.brd

R3456  Q_RES  100K 1% EMPTY  pkg 0402LF  page 128 : A = P3V3_AUX ; B = GPU_BASE_STBY_EN_BUF_R
C2485  Q_CAP  22UF 4V 20% X6S  pkg C0402  page 74 : A = PVDD11_S3_P1 ; B = GND

(kicad_pcb
	(version 20260206)
	(generator "pcbnew")
	(generator_version "10.0")
	(general
		(thickness 1.6)
		(legacy_teardrops no)
	)
	(paper "A4")
	(title_block
		(title "04192023_DAF0TMB3IC0_F0TG_MB_C_brd_V02_OCP.brd")
		(comment 1 "Grand Teton / footprints 532-533 of 8354")
	)
	(layers
		(0 "F.Cu" signal "TOP")
		(4 "In1.Cu" signal "GND")
		(6 "In2.Cu" signal "IN1")
		(8 "In3.Cu" signal "GND1")
		(10 "In4.Cu" signal "IN2")
		(12 "In5.Cu" signal "GND2")
		(14 "In6.Cu" signal "IN3")
		(16 "In7.Cu" signal "GND3")
		(18 "In8.Cu" signal "VCC")
		(20 "In9.Cu" signal "VCC1")
		(22 "In10.Cu" signal "GND4")
		(24 "In11.Cu" signal "IN4")
		(26 "In12.Cu" signal "GND5")
		(28 "In13.Cu" signal "IN5")
		(30 "In14.Cu" signal "GND6")
		(32 "In15.Cu" signal "IN6")
		(34 "In16.Cu" signal "GND7")
		(2 "B.Cu" signal "BOTTOM")
		(9 "F.Adhes" user "F.Adhesive")
		(11 "B.Adhes" user "B.Adhesive")
		(13 "F.Paste" user "Package Geometry/Pastemask Top")
		(15 "B.Paste" user "Package Geometry/Pastemask Bottom")
		(5 "F.SilkS" user "Ref Des/Silkscreen Top")
		(7 "B.SilkS" user "Ref Des/Silkscreen Bottom")
		(1 "F.Mask" user "Board Geometry/Soldermask Top")
		(3 "B.Mask" user "Board Geometry/Soldermask Bottom")
		(17 "Dwgs.User" user "User.Drawings")
		(19 "Cmts.User" user "User.Comments")
		(21 "Eco1.User" user "User.Eco1")
		(23 "Eco2.User" user "User.Eco2")
		(25 "Edge.Cuts" user "Board Geometry/Outline")
		(27 "Margin" user)
		(31 "F.CrtYd" user "Package Geometry/Place Bound Top")
		(29 "B.CrtYd" user "Package Geometry/Place Bound Bottom")
		(35 "F.Fab" user "Ref Des/Assembly Top")
		(33 "B.Fab" user "Ref Des/Assembly Bottom")
	)
	(footprint ""
		(layer "F.Cu")
		(at 115.277138 -261.748016 -90)
		(property "Reference" "C2485"
			(at 0 0 270)
			(layer "F.SilkS")
			(hide yes)
			(effects
				(font
					(size 1.27 1.27)
				)
			)
		)
		(property "Value" ""
			(at 0 0 270)
			(layer "F.Fab")
			(effects
				(font
					(size 1.27 1.27)
				)
			)
		)
		(duplicate_pad_numbers_are_jumpers no)
		(fp_line
			(start -0.7874 0.4064)
			(end -0.7874 -0.4064)
			(stroke
				(width 0.1524)
				(type default)
			)
			(layer "F.SilkS")
		)
		(fp_line
			(start 0.7874 0.4064)
			(end -0.7874 0.4064)
			(stroke
				(width 0.1524)
				(type default)
			)
			(layer "F.SilkS")
		)
		(fp_line
			(start -0.7874 -0.4064)
			(end 0.7874 -0.4064)
			(stroke
				(width 0.1524)
				(type default)
			)
			(layer "F.SilkS")
		)
		(fp_line
			(start 0.7874 -0.4064)
			(end 0.7874 0.4064)
			(stroke
				(width 0.1524)
				(type default)
			)
			(layer "F.SilkS")
		)
		(fp_line
			(start -0.67945 0.3048)
			(end -0.67945 -0.305054)
			(stroke
				(width 0.1)
				(type default)
			)
			(layer "F.Fab")
		)
		(fp_line
			(start -0.12065 0.3048)
			(end -0.67945 0.3048)
			(stroke
				(width 0.1)
				(type default)
			)
			(layer "F.Fab")
		)
		(fp_line
			(start 0.120396 0.3048)
			(end 0.120396 0.2794)
			(stroke
				(width 0.1)
				(type default)
			)
			(layer "F.Fab")
		)
		(fp_line
			(start 0.67945 0.3048)
			(end 0.120396 0.3048)
			(stroke
				(width 0.1)
				(type default)
			)
			(layer "F.Fab")
		)
		(fp_line
			(start -0.12065 0.2794)
			(end -0.12065 0.3048)
			(stroke
				(width 0.1)
				(type default)
			)
			(layer "F.Fab")
		)
		(fp_line
			(start 0.120396 0.2794)
			(end -0.12065 0.2794)
			(stroke
				(width 0.1)
				(type default)
			)
			(layer "F.Fab")
		)
		(fp_line
			(start -0.12065 -0.2794)
			(end 0.12065 -0.2794)
			(stroke
				(width 0.1)
				(type default)
			)
			(layer "F.Fab")
		)
		(fp_line
			(start 0.12065 -0.2794)
			(end 0.12065 -0.3048)
			(stroke
				(width 0.1)
				(type default)
			)
			(layer "F.Fab")
		)
		(fp_line
			(start 0.12065 -0.3048)
			(end 0.67945 -0.3048)
			(stroke
				(width 0.1)
				(type default)
			)
			(layer "F.Fab")
		)
		(fp_line
			(start 0.67945 -0.3048)
			(end 0.67945 0.3048)
			(stroke
				(width 0.1)
				(type default)
			)
			(layer "F.Fab")
		)
		(fp_line
			(start -0.67945 -0.305054)
			(end -0.12065 -0.305054)
			(stroke
				(width 0.1)
				(type default)
			)
			(layer "F.Fab")
		)
		(fp_line
			(start -0.12065 -0.305054)
			(end -0.12065 -0.2794)
			(stroke
				(width 0.1)
				(type default)
			)
			(layer "F.Fab")
		)
		(pad "1" smd circle
			(at -0.40005 0 270)
			(size 0 0)
			(layers "F.Cu" "F.Mask" "F.Paste")
			(net "PVDD11_S3_P1")
		)
		(pad "2" smd circle
			(at 0.40005 0 270)
			(size 0 0)
			(layers "F.Cu" "F.Mask" "F.Paste")
			(net "GND")
		)
	)
	(footprint ""
		(layer "F.Cu")
		(at 118.491 -424.688 180)
		(property "Reference" "R3456"
			(at 0 0 180)
			(layer "F.SilkS")
			(hide yes)
			(effects
				(font
					(size 1.27 1.27)
				)
			)
		)
		(property "Value" ""
			(at 0 0 180)
			(layer "F.Fab")
			(effects
				(font
					(size 1.27 1.27)
				)
			)
		)
		(duplicate_pad_numbers_are_jumpers no)
		(fp_line
			(start 0.7874 0.4064)
			(end -0.7874 0.4064)
			(stroke
				(width 0.1524)
				(type default)
			)
			(layer "F.SilkS")
		)
		(fp_line
			(start 0.7874 -0.4064)
			(end 0.7874 0.4064)
			(stroke
				(width 0.1524)
				(type default)
			)
			(layer "F.SilkS")
		)
		(fp_line
			(start -0.7874 0.4064)
			(end -0.7874 -0.4064)
			(stroke
				(width 0.1524)
				(type default)
			)
			(layer "F.SilkS")
		)
		(fp_line
			(start -0.7874 -0.4064)
			(end 0.7874 -0.4064)
			(stroke
				(width 0.1524)
				(type default)
			)
			(layer "F.SilkS")
		)
		(fp_line
			(start 0.67945 0.3048)
			(end 0.120396 0.3048)
			(stroke
				(width 0.1)
				(type default)
			)
			(layer "F.Fab")
		)
		(fp_line
			(start 0.67945 -0.3048)
			(end 0.67945 0.3048)
			(stroke
				(width 0.1)
				(type default)
			)
			(layer "F.Fab")
		)
		(fp_line
			(start 0.12065 -0.2794)
			(end 0.12065 -0.3048)
			(stroke
				(width 0.1)
				(type default)
			)
			(layer "F.Fab")
		)
		(fp_line
			(start 0.12065 -0.3048)
			(end 0.67945 -0.3048)
			(stroke
				(width 0.1)
				(type default)
			)
			(layer "F.Fab")
		)
		(fp_line
			(start 0.120396 0.3048)
			(end 0.120396 0.2794)
			(stroke
				(width 0.1)
				(type default)
			)
			(layer "F.Fab")
		)
		(fp_line
			(start 0.120396 0.2794)
			(end -0.12065 0.2794)
			(stroke
				(width 0.1)
				(type default)
			)
			(layer "F.Fab")
		)
		(fp_line
			(start -0.12065 0.3048)
			(end -0.67945 0.3048)
			(stroke
				(width 0.1)
				(type default)
			)
			(layer "F.Fab")
		)
		(fp_line
			(start -0.12065 0.2794)
			(end -0.12065 0.3048)
			(stroke
				(width 0.1)
				(type default)
			)
			(layer "F.Fab")
		)
		(fp_line
			(start -0.12065 -0.2794)
			(end 0.12065 -0.2794)
			(stroke
				(width 0.1)
				(type default)
			)
			(layer "F.Fab")
		)
		(fp_line
			(start -0.12065 -0.305054)
			(end -0.12065 -0.2794)
			(stroke
				(width 0.1)
				(type default)
			)
			(layer "F.Fab")
		)
		(fp_line
			(start -0.67945 0.3048)
			(end -0.67945 -0.305054)
			(stroke
				(width 0.1)
				(type default)
			)
			(layer "F.Fab")
		)
		(fp_line
			(start -0.67945 -0.305054)
			(end -0.12065 -0.305054)
			(stroke
				(width 0.1)
				(type default)
			)
			(layer "F.Fab")
		)
		(pad "1" smd circle
			(at -0.40005 0 180)
			(size 0 0)
			(layers "F.Cu" "F.Mask" "F.Paste")
			(net "P3V3_AUX")
		)
		(pad "2" smd circle
			(at 0.40005 0 180)
			(size 0 0)
			(layers "F.Cu" "F.Mask" "F.Paste")
			(net "GPU_BASE_STBY_EN_BUF_R")
		)
	)
)
